# T6G (Grand Teton) — schematic netlist excerpt (pin names and nets, part order shuffled) for the footprints in the layout excerpt that follows; sources: Cadence DE-HDL packaged netlist, KiCad conversion of 04192023_DAF0TMB3IC0_F0TG_MB_C_brd_V02_OCP.brd

C6681  Q_CAP_DIFFBUS  DIFF BUS_0.22UF 6.3V 20% X6S  pkg C0201  page 330 : \1\ = P5E_CPU1_P1_TX_BUF_C_DP<10> ; \2\ = P5E_CPU1_P1_TX_BUF_DP<10>
C6084  Q_CAP  0.1UF 25V 10% EMPTY  pkg 0402  page 267 : A = U142_VS ; B = GND
PR244  Q_RES  9.53K 1% CHIP  pkg 0402LF  page 217 : A = PVDDCR_CPU1_P1_EN1_ADDR_CFG ; B = GND

(kicad_pcb
	(version 20260206)
	(generator "pcbnew")
	(generator_version "10.0")
	(general
		(thickness 1.6)
		(legacy_teardrops no)
	)
	(paper "A4")
	(title_block
		(title "04192023_DAF0TMB3IC0_F0TG_MB_C_brd_V02_OCP.brd")
		(comment 1 "Grand Teton / footprints 7199-7201 of 8354")
	)
	(layers
		(0 "F.Cu" signal "TOP")
		(4 "In1.Cu" signal "GND")
		(6 "In2.Cu" signal "IN1")
		(8 "In3.Cu" signal "GND1")
		(10 "In4.Cu" signal "IN2")
		(12 "In5.Cu" signal "GND2")
		(14 "In6.Cu" signal "IN3")
		(16 "In7.Cu" signal "GND3")
		(18 "In8.Cu" signal "VCC")
		(20 "In9.Cu" signal "VCC1")
		(22 "In10.Cu" signal "GND4")
		(24 "In11.Cu" signal "IN4")
		(26 "In12.Cu" signal "GND5")
		(28 "In13.Cu" signal "IN5")
		(30 "In14.Cu" signal "GND6")
		(32 "In15.Cu" signal "IN6")
		(34 "In16.Cu" signal "GND7")
		(2 "B.Cu" signal "BOTTOM")
		(9 "F.Adhes" user "F.Adhesive")
		(11 "B.Adhes" user "B.Adhesive")
		(13 "F.Paste" user "Package Geometry/Pastemask Top")
		(15 "B.Paste" user "Package Geometry/Pastemask Bottom")
		(5 "F.SilkS" user "Ref Des/Silkscreen Top")
		(7 "B.SilkS" user "Ref Des/Silkscreen Bottom")
		(1 "F.Mask" user "Board Geometry/Soldermask Top")
		(3 "B.Mask" user "Board Geometry/Soldermask Bottom")
		(17 "Dwgs.User" user "User.Drawings")
		(19 "Cmts.User" user "User.Comments")
		(21 "Eco1.User" user "User.Eco1")
		(23 "Eco2.User" user "User.Eco2")
		(25 "Edge.Cuts" user "Board Geometry/Outline")
		(27 "Margin" user)
		(31 "F.CrtYd" user "Package Geometry/Place Bound Top")
		(29 "B.CrtYd" user "Package Geometry/Place Bound Bottom")
		(35 "F.Fab" user "Ref Des/Assembly Top")
		(33 "B.Fab" user "Ref Des/Assembly Bottom")
	)
	(footprint ""
		(layer "B.Cu")
		(at 179.27701 -421.374824 90)
		(property "Reference" "C6084"
			(at 0 0 90)
			(layer "B.SilkS")
			(hide yes)
			(effects
				(font
					(size 1.27 1.27)
				)
				(justify mirror)
			)
		)
		(property "Value" ""
			(at 0 0 90)
			(layer "B.Fab")
			(effects
				(font
					(size 1.27 1.27)
				)
				(justify mirror)
			)
		)
		(duplicate_pad_numbers_are_jumpers no)
		(fp_line
			(start 0.7874 -0.4064)
			(end -0.7874 -0.4064)
			(stroke
				(width 0.1524)
				(type default)
			)
			(layer "B.SilkS")
		)
		(fp_line
			(start -0.7874 -0.4064)
			(end -0.7874 0.4064)
			(stroke
				(width 0.1524)
				(type default)
			)
			(layer "B.SilkS")
		)
		(fp_line
			(start 0.7874 0.4064)
			(end 0.7874 -0.4064)
			(stroke
				(width 0.1524)
				(type default)
			)
			(layer "B.SilkS")
		)
		(fp_line
			(start -0.7874 0.4064)
			(end 0.7874 0.4064)
			(stroke
				(width 0.1524)
				(type default)
			)
			(layer "B.SilkS")
		)
		(fp_line
			(start 0.67945 -0.305054)
			(end 0.12065 -0.305054)
			(stroke
				(width 0.1)
				(type default)
			)
			(layer "B.Fab")
		)
		(fp_line
			(start 0.12065 -0.305054)
			(end 0.12065 -0.2794)
			(stroke
				(width 0.1)
				(type default)
			)
			(layer "B.Fab")
		)
		(fp_line
			(start -0.12065 -0.3048)
			(end -0.67945 -0.3048)
			(stroke
				(width 0.1)
				(type default)
			)
			(layer "B.Fab")
		)
		(fp_line
			(start -0.67945 -0.3048)
			(end -0.67945 0.3048)
			(stroke
				(width 0.1)
				(type default)
			)
			(layer "B.Fab")
		)
		(fp_line
			(start 0.12065 -0.2794)
			(end -0.12065 -0.2794)
			(stroke
				(width 0.1)
				(type default)
			)
			(layer "B.Fab")
		)
		(fp_line
			(start -0.12065 -0.2794)
			(end -0.12065 -0.3048)
			(stroke
				(width 0.1)
				(type default)
			)
			(layer "B.Fab")
		)
		(fp_line
			(start 0.12065 0.2794)
			(end 0.12065 0.3048)
			(stroke
				(width 0.1)
				(type default)
			)
			(layer "B.Fab")
		)
		(fp_line
			(start -0.120396 0.2794)
			(end 0.12065 0.2794)
			(stroke
				(width 0.1)
				(type default)
			)
			(layer "B.Fab")
		)
		(fp_line
			(start 0.67945 0.3048)
			(end 0.67945 -0.305054)
			(stroke
				(width 0.1)
				(type default)
			)
			(layer "B.Fab")
		)
		(fp_line
			(start 0.12065 0.3048)
			(end 0.67945 0.3048)
			(stroke
				(width 0.1)
				(type default)
			)
			(layer "B.Fab")
		)
		(fp_line
			(start -0.120396 0.3048)
			(end -0.120396 0.2794)
			(stroke
				(width 0.1)
				(type default)
			)
			(layer "B.Fab")
		)
		(fp_line
			(start -0.67945 0.3048)
			(end -0.120396 0.3048)
			(stroke
				(width 0.1)
				(type default)
			)
			(layer "B.Fab")
		)
		(pad "1" smd circle
			(at 0.40005 0 270)
			(size 0 0)
			(layers "B.Cu" "B.Mask" "B.Paste")
			(net "U142_VS")
		)
		(pad "2" smd circle
			(at -0.40005 0 270)
			(size 0 0)
			(layers "B.Cu" "B.Mask" "B.Paste")
			(net "GND")
		)
	)
	(footprint ""
		(layer "B.Cu")
		(at 80.847184 -408.517344 90)
		(property "Reference" "C6681"
			(at 0 0 90)
			(layer "B.SilkS")
			(hide yes)
			(effects
				(font
					(size 1.27 1.27)
				)
				(justify mirror)
			)
		)
		(property "Value" ""
			(at 0 0 90)
			(layer "B.Fab")
			(effects
				(font
					(size 1.27 1.27)
				)
				(justify mirror)
			)
		)
		(duplicate_pad_numbers_are_jumpers no)
		(fp_line
			(start 0.299974 -0.150114)
			(end -0.299974 -0.150114)
			(stroke
				(width 0.1)
				(type default)
			)
			(layer "B.Fab")
		)
		(fp_line
			(start -0.299974 -0.150114)
			(end -0.299974 0.150114)
			(stroke
				(width 0.1)
				(type default)
			)
			(layer "B.Fab")
		)
		(fp_line
			(start 0.299974 0.150114)
			(end 0.299974 -0.150114)
			(stroke
				(width 0.1)
				(type default)
			)
			(layer "B.Fab")
		)
		(fp_line
			(start -0.299974 0.150114)
			(end 0.299974 0.150114)
			(stroke
				(width 0.1)
				(type default)
			)
			(layer "B.Fab")
		)
		(pad "1" smd rect
			(at 0.2667 0 270)
			(size 0.3048 0.381)
			(layers "B.Cu" "B.Mask" "B.Paste")
			(net "P5E_CPU1_P1_TX_BUF_C_DP<10>")
		)
		(pad "2" smd rect
			(at -0.2667 0 270)
			(size 0.3048 0.381)
			(layers "B.Cu" "B.Mask" "B.Paste")
			(net "P5E_CPU1_P1_TX_BUF_DP<10>")
		)
	)
	(footprint ""
		(layer "B.Cu")
		(at 32.639 -364.871)
		(property "Reference" "PR244"
			(at 0 0 0)
			(layer "B.SilkS")
			(hide yes)
			(effects
				(font
					(size 1.27 1.27)
				)
				(justify mirror)
			)
		)
		(property "Value" ""
			(at 0 0 0)
			(layer "B.Fab")
			(effects
				(font
					(size 1.27 1.27)
				)
				(justify mirror)
			)
		)
		(duplicate_pad_numbers_are_jumpers no)
		(fp_line
			(start -0.7874 -0.4064)
			(end -0.7874 0.4064)
			(stroke
				(width 0.1524)
				(type default)
			)
			(layer "B.SilkS")
		)
		(fp_line
			(start -0.7874 0.4064)
			(end 0.7874 0.4064)
			(stroke
				(width 0.1524)
				(type default)
			)
			(layer "B.SilkS")
		)
		(fp_line
			(start 0.7874 -0.4064)
			(end -0.7874 -0.4064)
			(stroke
				(width 0.1524)
				(type default)
			)
			(layer "B.SilkS")
		)
		(fp_line
			(start 0.7874 0.4064)
			(end 0.7874 -0.4064)
			(stroke
				(width 0.1524)
				(type default)
			)
			(layer "B.SilkS")
		)
		(fp_line
			(start -0.67945 -0.3048)
			(end -0.67945 0.3048)
			(stroke
				(width 0.1)
				(type default)
			)
			(layer "B.Fab")
		)
		(fp_line
			(start -0.67945 0.3048)
			(end -0.120396 0.3048)
			(stroke
				(width 0.1)
				(type default)
			)
			(layer "B.Fab")
		)
		(fp_line
			(start -0.12065 -0.3048)
			(end -0.67945 -0.3048)
			(stroke
				(width 0.1)
				(type default)
			)
			(layer "B.Fab")
		)
		(fp_line
			(start -0.12065 -0.2794)
			(end -0.12065 -0.3048)
			(stroke
				(width 0.1)
				(type default)
			)
			(layer "B.Fab")
		)
		(fp_line
			(start -0.120396 0.2794)
			(end 0.12065 0.2794)
			(stroke
				(width 0.1)
				(type default)
			)
			(layer "B.Fab")
		)
		(fp_line
			(start -0.120396 0.3048)
			(end -0.120396 0.2794)
			(stroke
				(width 0.1)
				(type default)
			)
			(layer "B.Fab")
		)
		(fp_line
			(start 0.12065 -0.305054)
			(end 0.12065 -0.2794)
			(stroke
				(width 0.1)
				(type default)
			)
			(layer "B.Fab")
		)
		(fp_line
			(start 0.12065 -0.2794)
			(end -0.12065 -0.2794)
			(stroke
				(width 0.1)
				(type default)
			)
			(layer "B.Fab")
		)
		(fp_line
			(start 0.12065 0.2794)
			(end 0.12065 0.3048)
			(stroke
				(width 0.1)
				(type default)
			)
			(layer "B.Fab")
		)
		(fp_line
			(start 0.12065 0.3048)
			(end 0.67945 0.3048)
			(stroke
				(width 0.1)
				(type default)
			)
			(layer "B.Fab")
		)
		(fp_line
			(start 0.67945 -0.305054)
			(end 0.12065 -0.305054)
			(stroke
				(width 0.1)
				(type default)
			)
			(layer "B.Fab")
		)
		(fp_line
			(start 0.67945 0.3048)
			(end 0.67945 -0.305054)
			(stroke
				(width 0.1)
				(type default)
			)
			(layer "B.Fab")
		)
		(pad "1" smd circle
			(at 0.40005 0 180)
			(size 0 0)
			(layers "B.Cu" "B.Mask" "B.Paste")
			(net "PVDDCR_CPU1_P1_EN1_ADDR_CFG")
		)
		(pad "2" smd circle
			(at -0.40005 0 180)
			(size 0 0)
			(layers "B.Cu" "B.Mask" "B.Paste")
			(net "GND")
		)
	)
)
